(kicad_pcb
	(version 20260206)
	(generator "pcbnew")
	(generator_version "10.0")
	(general
		(thickness 1.6)
		(legacy_teardrops no)
	)
	(paper "A4")
	(title_block
		(title "dpb — 14545-sa.0730WZS0815.brd")
		(comment 1 "Honey Badger (Wiwynn) / footprints 455-459 of 1066")
	)
	(layers
		(0 "F.Cu" signal "TOP")
		(4 "In1.Cu" signal "L2GND")
		(6 "In2.Cu" signal "L3")
		(8 "In3.Cu" signal "L4VCC")
		(10 "In4.Cu" signal "L5VCC")
		(12 "In5.Cu" signal "L6")
		(14 "In6.Cu" signal "L7GND")
		(2 "B.Cu" signal "BOTTOM")
		(9 "F.Adhes" user "F.Adhesive")
		(11 "B.Adhes" user "B.Adhesive")
		(13 "F.Paste" user "Package Geometry/Pastemask Top")
		(15 "B.Paste" user "Package Geometry/Pastemask Bottom")
		(5 "F.SilkS" user "Ref Des/Silkscreen Top")
		(7 "B.SilkS" user "Ref Des/Silkscreen Bottom")
		(1 "F.Mask" user "Board Geometry/Soldermask Top")
		(3 "B.Mask" user "Board Geometry/Soldermask Bottom")
		(17 "Dwgs.User" user "User.Drawings")
		(19 "Cmts.User" user "User.Comments")
		(21 "Eco1.User" user "User.Eco1")
		(23 "Eco2.User" user "User.Eco2")
		(25 "Edge.Cuts" user "Board Geometry/Outline")
		(27 "Margin" user)
		(31 "F.CrtYd" user "Package Geometry/Place Bound Top")
		(29 "B.CrtYd" user "Package Geometry/Place Bound Bottom")
		(35 "F.Fab" user "Ref Des/Assembly Top")
		(33 "B.Fab" user "Ref Des/Assembly Bottom")
	)
	(footprint ""
		(layer "F.Cu")
		(at 85.343746 -16.0147 90)
		(property "Reference" "R474"
			(at 0 0 90)
			(layer "F.SilkS")
			(hide yes)
			(effects
				(font
					(size 1.27 1.27)
				)
			)
		)
		(property "Value" "4K7R2J-2-GP"
			(at 0.064008 -3.993896 90)
			(unlocked yes)
			(layer "F.Fab")
			(hide yes)
			(effects
				(font
					(size 1.016 1.016)
					(thickness 0.1524)
				)
			)
		)
		(property "Device Type" "R402H16"
			(at 0.064008 -5.517896 90)
			(unlocked yes)
			(layer "F.Fab")
			(hide yes)
			(effects
				(font
					(size 1.016 1.016)
					(thickness 0.1524)
				)
			)
		)
		(duplicate_pad_numbers_are_jumpers no)
		(fp_line
			(start 0.508 -0.9398)
			(end -0.508 -0.9398)
			(stroke
				(width 0.1524)
				(type default)
			)
			(layer "F.SilkS")
		)
		(fp_line
			(start -0.508 -0.9398)
			(end -0.508 0.9398)
			(stroke
				(width 0.1524)
				(type default)
			)
			(layer "F.SilkS")
		)
		(fp_rect
			(start -0.508 0.9398)
			(end 0.508 -0.9398)
			(stroke
				(width 0)
				(type default)
			)
			(fill no)
			(layer "F.CrtYd")
		)
		(fp_rect
			(start -0.508 0.9398)
			(end 0.508 -0.9398)
			(stroke
				(width 0)
				(type default)
			)
			(fill no)
			(layer "F.Fab")
		)
		(pad "1" smd custom
			(at 0 -0.4445 90)
			(size 0.1397 0.1397)
			(layers "F.Cu" "F.Mask" "F.Paste")
			(net "P3V3")
			(options
				(clearance outline)
				(anchor circle)
			)
			(primitives
				(gr_poly
					(pts
						(arc
							(start -0.1778 -0.2794)
							(mid -0.249642 -0.249642)
							(end -0.2794 -0.1778)
						)
						(arc
							(start -0.2794 0.1778)
							(mid -0.249642 0.249642)
							(end -0.1778 0.2794)
						)
						(arc
							(start 0.1778 0.2794)
							(mid 0.249642 0.249642)
							(end 0.2794 0.1778)
						)
						(arc
							(start 0.2794 -0.1778)
							(mid 0.249642 -0.249642)
							(end 0.1778 -0.2794)
						)
					)
					(width 0)
					(fill yes)
				)
			)
		)
		(pad "2" smd custom
			(at 0 0.4445 90)
			(size 0.1397 0.1397)
			(layers "F.Cu" "F.Mask" "F.Paste")
			(net "SAS2X28_A_HDD14_FLT")
			(options
				(clearance outline)
				(anchor circle)
			)
			(primitives
				(gr_poly
					(pts
						(arc
							(start -0.1778 -0.2794)
							(mid -0.249642 -0.249642)
							(end -0.2794 -0.1778)
						)
						(arc
							(start -0.2794 0.1778)
							(mid -0.249642 0.249642)
							(end -0.1778 0.2794)
						)
						(arc
							(start 0.1778 0.2794)
							(mid 0.249642 0.249642)
							(end 0.2794 0.1778)
						)
						(arc
							(start 0.2794 -0.1778)
							(mid 0.249642 -0.249642)
							(end 0.1778 -0.2794)
						)
					)
					(width 0)
					(fill yes)
				)
			)
		)
	)
	(footprint ""
		(layer "F.Cu")
		(at 214.841582 -276.197568 90)
		(property "Reference" "R133"
			(at 0 0 90)
			(layer "F.SilkS")
			(hide yes)
			(effects
				(font
					(size 1.27 1.27)
				)
			)
		)
		(property "Value" "4K7R2J-2-GP"
			(at 0.064008 -3.993896 90)
			(unlocked yes)
			(layer "F.Fab")
			(hide yes)
			(effects
				(font
					(size 1.016 1.016)
					(thickness 0.1524)
				)
			)
		)
		(property "Device Type" "R402H16"
			(at 0.064008 -5.517896 90)
			(unlocked yes)
			(layer "F.Fab")
			(hide yes)
			(effects
				(font
					(size 1.016 1.016)
					(thickness 0.1524)
				)
			)
		)
		(duplicate_pad_numbers_are_jumpers no)
		(fp_line
			(start 0.508 -0.9398)
			(end -0.508 -0.9398)
			(stroke
				(width 0.1524)
				(type default)
			)
			(layer "F.SilkS")
		)
		(fp_line
			(start -0.508 -0.9398)
			(end -0.508 0.9398)
			(stroke
				(width 0.1524)
				(type default)
			)
			(layer "F.SilkS")
		)
		(fp_rect
			(start -0.508 0.9398)
			(end 0.508 -0.9398)
			(stroke
				(width 0)
				(type default)
			)
			(fill no)
			(layer "F.CrtYd")
		)
		(fp_rect
			(start -0.508 0.9398)
			(end 0.508 -0.9398)
			(stroke
				(width 0)
				(type default)
			)
			(fill no)
			(layer "F.Fab")
		)
		(pad "1" smd custom
			(at 0 -0.4445 90)
			(size 0.1397 0.1397)
			(layers "F.Cu" "F.Mask" "F.Paste")
			(net "P3V3")
			(options
				(clearance outline)
				(anchor circle)
			)
			(primitives
				(gr_poly
					(pts
						(arc
							(start -0.1778 -0.2794)
							(mid -0.249642 -0.249642)
							(end -0.2794 -0.1778)
						)
						(arc
							(start -0.2794 0.1778)
							(mid -0.249642 0.249642)
							(end -0.1778 0.2794)
						)
						(arc
							(start 0.1778 0.2794)
							(mid 0.249642 0.249642)
							(end 0.2794 0.1778)
						)
						(arc
							(start 0.2794 -0.1778)
							(mid 0.249642 -0.249642)
							(end 0.1778 -0.2794)
						)
					)
					(width 0)
					(fill yes)
				)
			)
		)
		(pad "2" smd custom
			(at 0 0.4445 90)
			(size 0.1397 0.1397)
			(layers "F.Cu" "F.Mask" "F.Paste")
			(net "HDD_PRSNT_NET2")
			(options
				(clearance outline)
				(anchor circle)
			)
			(primitives
				(gr_poly
					(pts
						(arc
							(start -0.1778 -0.2794)
							(mid -0.249642 -0.249642)
							(end -0.2794 -0.1778)
						)
						(arc
							(start -0.2794 0.1778)
							(mid -0.249642 0.249642)
							(end -0.1778 0.2794)
						)
						(arc
							(start 0.1778 0.2794)
							(mid 0.249642 0.249642)
							(end 0.2794 0.1778)
						)
						(arc
							(start 0.2794 -0.1778)
							(mid 0.249642 -0.249642)
							(end 0.1778 -0.2794)
						)
					)
					(width 0)
					(fill yes)
				)
			)
		)
	)
	(footprint ""
		(layer "F.Cu")
		(at 55.9562 -497.6114 180)
		(property "Reference" "C192"
			(at 0 0 180)
			(layer "F.SilkS")
			(hide yes)
			(effects
				(font
					(size 1.27 1.27)
				)
			)
		)
		(property "Value" "SC10U25V6KX-1GP"
			(at -0.0762 -5.1308 180)
			(unlocked yes)
			(layer "F.Fab")
			(hide yes)
			(effects
				(font
					(size 1.016 1.016)
					(thickness 0.1524)
				)
			)
		)
		(property "Device Type" "C1206H71"
			(at -0.127 -6.6548 180)
			(unlocked yes)
			(layer "F.Fab")
			(hide yes)
			(effects
				(font
					(size 1.016 1.016)
					(thickness 0.1524)
				)
			)
		)
		(duplicate_pad_numbers_are_jumpers no)
		(fp_line
			(start 1.016 2.2352)
			(end -1.016 2.2352)
			(stroke
				(width 0.1524)
				(type default)
			)
			(layer "F.SilkS")
		)
		(fp_line
			(start 1.016 0.8382)
			(end 1.016 2.2352)
			(stroke
				(width 0.1524)
				(type default)
			)
			(layer "F.SilkS")
		)
		(fp_line
			(start 1.016 -2.2352)
			(end 1.016 -0.8382)
			(stroke
				(width 0.1524)
				(type default)
			)
			(layer "F.SilkS")
		)
		(fp_line
			(start -1.016 2.2352)
			(end -1.016 0.8382)
			(stroke
				(width 0.1524)
				(type default)
			)
			(layer "F.SilkS")
		)
		(fp_line
			(start -1.016 -0.8382)
			(end -1.016 -2.2352)
			(stroke
				(width 0.1524)
				(type default)
			)
			(layer "F.SilkS")
		)
		(fp_line
			(start -1.016 -2.2352)
			(end 1.016 -2.2352)
			(stroke
				(width 0.1524)
				(type default)
			)
			(layer "F.SilkS")
		)
		(fp_rect
			(start -1.0922 2.3114)
			(end 1.0922 -2.3114)
			(stroke
				(width 0)
				(type default)
			)
			(fill no)
			(layer "F.CrtYd")
		)
		(fp_poly
			(pts
				(xy 1.0922 -2.3114) (xy 1.0922 2.3114) (xy -1.0922 2.3114) (xy -1.0922 -2.3114)
			)
			(stroke
				(width 0)
				(type default)
			)
			(fill no)
			(layer "F.Fab")
		)
		(pad "1" smd rect
			(at 0 -1.397 180)
			(size 1.651 1.27)
			(layers "F.Cu" "F.Mask" "F.Paste")
			(net "P12V_HDD5")
		)
		(pad "2" smd rect
			(at 0 1.397 180)
			(size 1.651 1.27)
			(layers "F.Cu" "F.Mask" "F.Paste")
			(net "GND")
		)
	)
	(footprint ""
		(layer "F.Cu")
		(at 80.4418 -401.9804 -90)
		(property "Reference" "R414"
			(at 0 0 270)
			(layer "F.SilkS")
			(hide yes)
			(effects
				(font
					(size 1.27 1.27)
				)
			)
		)
		(property "Value" "0R2J-2-GP"
			(at 0.064008 -3.993896 270)
			(unlocked yes)
			(layer "F.Fab")
			(hide yes)
			(effects
				(font
					(size 1.016 1.016)
					(thickness 0.1524)
				)
			)
		)
		(property "Device Type" "R402H16"
			(at 0.064008 -5.517896 270)
			(unlocked yes)
			(layer "F.Fab")
			(hide yes)
			(effects
				(font
					(size 1.016 1.016)
					(thickness 0.1524)
				)
			)
		)
		(duplicate_pad_numbers_are_jumpers no)
		(fp_line
			(start -0.508 -0.9398)
			(end -0.508 0.9398)
			(stroke
				(width 0.1524)
				(type default)
			)
			(layer "F.SilkS")
		)
		(fp_line
			(start 0.508 -0.9398)
			(end -0.508 -0.9398)
			(stroke
				(width 0.1524)
				(type default)
			)
			(layer "F.SilkS")
		)
		(fp_rect
			(start -0.508 0.9398)
			(end 0.508 -0.9398)
			(stroke
				(width 0)
				(type default)
			)
			(fill no)
			(layer "F.CrtYd")
		)
		(fp_rect
			(start -0.508 0.9398)
			(end 0.508 -0.9398)
			(stroke
				(width 0)
				(type default)
			)
			(fill no)
			(layer "F.Fab")
		)
		(pad "1" smd custom
			(at 0 -0.4445 270)
			(size 0.1397 0.1397)
			(layers "F.Cu" "F.Mask" "F.Paste")
			(net "SW_HDD6_G")
			(options
				(clearance outline)
				(anchor circle)
			)
			(primitives
				(gr_poly
					(pts
						(arc
							(start -0.1778 -0.2794)
							(mid -0.249642 -0.249642)
							(end -0.2794 -0.1778)
						)
						(arc
							(start -0.2794 0.1778)
							(mid -0.249642 0.249642)
							(end -0.1778 0.2794)
						)
						(arc
							(start 0.1778 0.2794)
							(mid 0.249642 0.249642)
							(end 0.2794 0.1778)
						)
						(arc
							(start 0.2794 -0.1778)
							(mid 0.249642 -0.249642)
							(end 0.1778 -0.2794)
						)
					)
					(width 0)
					(fill yes)
				)
			)
		)
		(pad "2" smd custom
			(at 0 0.4445 270)
			(size 0.1397 0.1397)
			(layers "F.Cu" "F.Mask" "F.Paste")
			(net "SW_HDD6_R")
			(options
				(clearance outline)
				(anchor circle)
			)
			(primitives
				(gr_poly
					(pts
						(arc
							(start -0.1778 -0.2794)
							(mid -0.249642 -0.249642)
							(end -0.2794 -0.1778)
						)
						(arc
							(start -0.2794 0.1778)
							(mid -0.249642 0.249642)
							(end -0.1778 0.2794)
						)
						(arc
							(start 0.1778 0.2794)
							(mid 0.249642 0.249642)
							(end 0.2794 0.1778)
						)
						(arc
							(start 0.2794 -0.1778)
							(mid 0.249642 -0.249642)
							(end 0.1778 -0.2794)
						)
					)
					(width 0)
					(fill yes)
				)
			)
		)
	)
	(footprint ""
		(layer "F.Cu")
		(at 39.248334 -30.499558 180)
		(property "Reference" "PTC3"
			(at 0 0 180)
			(layer "F.SilkS")
			(hide yes)
			(effects
				(font
					(size 1.27 1.27)
				)
			)
		)
		(property "Value" "ST330U10VDM-2GP"
			(at 0 -9.6012 180)
			(unlocked yes)
			(layer "F.Fab")
			(hide yes)
			(effects
				(font
					(size 1.016 1.016)
					(thickness 0.1524)
				)
			)
		)
		(property "Device Type" "CT7343H150"
			(at 0 -11.1252 180)
			(unlocked yes)
			(layer "F.Fab")
			(hide yes)
			(effects
				(font
					(size 1.016 1.016)
					(thickness 0.1524)
				)
			)
		)
		(duplicate_pad_numbers_are_jumpers no)
		(fp_line
			(start 2.286 4.8768)
			(end -2.286 4.8768)
			(stroke
				(width 0.1524)
				(type default)
			)
			(layer "F.SilkS")
		)
		(fp_line
			(start 2.286 2.032)
			(end 2.286 4.8768)
			(stroke
				(width 0.1524)
				(type default)
			)
			(layer "F.SilkS")
		)
		(fp_line
			(start 2.286 -2.032)
			(end 2.286 -4.8768)
			(stroke
				(width 0.1524)
				(type default)
			)
			(layer "F.SilkS")
		)
		(fp_line
			(start 2.286 -4.8768)
			(end -2.286 -4.8768)
			(stroke
				(width 0.1524)
				(type default)
			)
			(layer "F.SilkS")
		)
		(fp_line
			(start 2.1082 -4.699)
			(end -2.1082 -4.699)
			(stroke
				(width 0.508)
				(type default)
			)
			(layer "F.SilkS")
		)
		(fp_line
			(start -2.286 4.8768)
			(end -2.286 2.032)
			(stroke
				(width 0.1524)
				(type default)
			)
			(layer "F.SilkS")
		)
		(fp_line
			(start -2.286 -4.8768)
			(end -2.286 -2.032)
			(stroke
				(width 0.1524)
				(type default)
			)
			(layer "F.SilkS")
		)
		(fp_rect
			(start -2.1463 3.6449)
			(end 2.1463 -3.6449)
			(stroke
				(width 0)
				(type default)
			)
			(fill no)
			(layer "F.CrtYd")
		)
		(fp_poly
			(pts
				(xy -2.54 4.953) (xy -2.54 4.2926) (xy -3.81 4.2926) (xy -3.81 -4.2926) (xy -2.54 -4.2926) (xy -2.54 -4.953)
				(xy 2.54 -4.953) (xy 2.54 -4.2926) (xy 3.81 -4.2926) (xy 3.81 -1.6256) (xy 2.1463 -1.6256) (xy 2.1463 -3.6449)
				(xy -2.1463 -3.6449) (xy -2.1463 3.6449) (xy 2.1463 3.6449) (xy 2.1463 -1.6129) (xy 3.81 -1.6129)
				(xy 3.81 4.2926) (xy 2.54 4.2926) (xy 2.54 4.953)
			)
			(stroke
				(width 0)
				(type default)
			)
			(fill no)
			(layer "F.CrtYd")
		)
		(fp_rect
			(start 2.54 4.2926)
			(end 3.81 -4.2926)
			(stroke
				(width 0)
				(type default)
			)
			(fill no)
			(layer "F.Fab")
		)
		(fp_rect
			(start -2.54 4.953)
			(end 2.54 -4.953)
			(stroke
				(width 0)
				(type default)
			)
			(fill no)
			(layer "F.Fab")
		)
		(fp_rect
			(start -3.81 4.2926)
			(end -2.54 -4.2926)
			(stroke
				(width 0)
				(type default)
			)
			(fill no)
			(layer "F.Fab")
		)
		(pad "1" smd rect
			(at 0 -3.1496 180)
			(size 2.413 2.286)
			(layers "F.Cu" "F.Mask" "F.Paste")
			(net "P5VB")
		)
		(pad "2" smd rect
			(at 0 3.1496 180)
			(size 2.413 2.286)
			(layers "F.Cu" "F.Mask" "F.Paste")
			(net "GND")
		)
		(zone
			(layer "F.Cu")
			(hatch none 0.5)
			(connect_pads
				(clearance 0)
			)
			(min_thickness 0.25)
			(keepout
				(tracks allowed)
				(vias not_allowed)
				(pads allowed)
				(copperpour not_allowed)
				(footprints allowed)
			)
			(placement
				(enabled no)
				(sheetname "")
			)
			(fill
				(thermal_gap 0.5)
				(thermal_bridge_width 0.5)
				(island_removal_mode 0)
			)
			(polygon
				(pts
					(xy 37.737034 -28.810458) (xy 37.737034 -25.902158) (xy 40.759634 -25.902158) (xy 40.759634 -28.797758)
					(xy 40.759634 -29.127958) (xy 37.737034 -29.127958)
				)
			)
		)
		(zone
			(layer "F.Cu")
			(hatch none 0.5)
			(connect_pads
				(clearance 0)
			)
			(min_thickness 0.25)
			(keepout
				(tracks allowed)
				(vias not_allowed)
				(pads allowed)
				(copperpour not_allowed)
				(footprints allowed)
			)
			(placement
				(enabled no)
				(sheetname "")
			)
			(fill
				(thermal_gap 0.5)
				(thermal_bridge_width 0.5)
				(island_removal_mode 0)
			)
			(polygon
				(pts
					(xy 40.759634 -35.096958) (xy 37.737034 -35.096958) (xy 37.737034 -32.201358) (xy 37.737034 -31.871158)
					(xy 40.759634 -31.871158) (xy 40.759634 -32.201358)
				)
			)
		)
	)
)
